(kicad_pcb
	(version 20260206)
	(generator "pcbnew")
	(generator_version "10.0")
	(general
		(thickness 1.6)
		(legacy_teardrops no)
	)
	(paper "A4")
	(title_block
		(title "01162023_DA0F0TEBIF0_F0T_Expander_BD_F_brd_V02_OCP.brd")
		(comment 1 "Grand Teton / footprint 1907 of 9728 (J14), pads 1-77 of 142")
	)
	(layers
		(0 "F.Cu" signal "TOP")
		(4 "In1.Cu" signal "GND")
		(6 "In2.Cu" signal "VCC")
		(8 "In3.Cu" signal "VCC1")
		(10 "In4.Cu" signal "GND1")
		(12 "In5.Cu" signal "IN1")
		(14 "In6.Cu" signal "GND2")
		(16 "In7.Cu" signal "IN2")
		(18 "In8.Cu" signal "GND3")
		(20 "In9.Cu" signal "IN3")
		(22 "In10.Cu" signal "GND4")
		(24 "In11.Cu" signal "IN4")
		(26 "In12.Cu" signal "GND5")
		(28 "In13.Cu" signal "IN5")
		(30 "In14.Cu" signal "GND6")
		(32 "In15.Cu" signal "IN6")
		(34 "In16.Cu" signal "GND7")
		(2 "B.Cu" signal "BOTTOM")
		(9 "F.Adhes" user "F.Adhesive")
		(11 "B.Adhes" user "B.Adhesive")
		(13 "F.Paste" user "Package Geometry/Pastemask Top")
		(15 "B.Paste" user "Package Geometry/Pastemask Bottom")
		(5 "F.SilkS" user "Ref Des/Silkscreen Top")
		(7 "B.SilkS" user "Ref Des/Silkscreen Bottom")
		(1 "F.Mask" user "Board Geometry/Soldermask Top")
		(3 "B.Mask" user "Board Geometry/Soldermask Bottom")
		(17 "Dwgs.User" user "User.Drawings")
		(19 "Cmts.User" user "User.Comments")
		(21 "Eco1.User" user "User.Eco1")
		(23 "Eco2.User" user "User.Eco2")
		(25 "Edge.Cuts" user "Board Geometry/Outline")
		(27 "Margin" user)
		(31 "F.CrtYd" user "Package Geometry/Place Bound Top")
		(29 "B.CrtYd" user "Package Geometry/Place Bound Bottom")
		(35 "F.Fab" user "Ref Des/Assembly Top")
		(33 "B.Fab" user "Ref Des/Assembly Bottom")
	)
	(footprint ""
		(layer "F.Cu")
		(at 375.489978 -412.090108)
		(property "Reference" "J14"
			(at 26.41727 7.51459 90)
			(unlocked yes)
			(layer "F.SilkS")
			(effects
				(font
					(size 2.032 1.524)
					(thickness 0.1524)
				)
				(justify left)
			)
		)
		(property "Value" ""
			(at 0 0 0)
			(layer "F.Fab")
			(effects
				(font
					(size 1.27 1.27)
				)
			)
		)
		(duplicate_pad_numbers_are_jumpers no)
		(pad "A1" thru_hole rect
			(at 0 0 180)
			(size 0.71628 0.71628)
			(drill 0.30988)
			(layers "*.Cu" "*.Mask")
			(remove_unused_layers no)
			(net "PRSNT_SWB_B1_N")
			(clearance 0.0508)
			(thermal_gap 0.0508)
			(padstack
				(mode front_inner_back)
				(layer "Inner"
					(shape circle)
					(size 0.71628 0.71628)
					(clearance 0.0508)
				)
				(layer "B.Cu"
					(shape rect)
					(size 0.71628 0.71628)
					(clearance 0.0508)
				)
			)
		)
		(pad "A2" thru_hole circle
			(at 2.199894 0.199898 180)
			(size 0.906272 0.906272)
			(drill 0.499872)
			(layers "*.Cu" "*.Mask")
			(remove_unused_layers no)
			(net "GND")
			(clearance 0.0508)
			(thermal_gap 0.0508)
		)
		(pad "A3" thru_hole circle
			(at 4.400042 0 180)
			(size 0.71628 0.71628)
			(drill 0.30988)
			(layers "*.Cu" "*.Mask")
			(remove_unused_layers no)
			(net "MB_SWB_PWRGD_BUF_R")
			(clearance 0.0508)
			(thermal_gap 0.0508)
		)
		(pad "A4" thru_hole circle
			(at 6.599936 0.199898 180)
			(size 0.906272 0.906272)
			(drill 0.499872)
			(layers "*.Cu" "*.Mask")
			(remove_unused_layers no)
			(net "GND")
			(clearance 0.0508)
			(thermal_gap 0.0508)
		)
		(pad "A5" thru_hole circle
			(at 8.800084 0 180)
			(size 0.71628 0.71628)
			(drill 0.30988)
			(layers "*.Cu" "*.Mask")
			(remove_unused_layers no)
			(net "Net_8872")
			(clearance 0.0508)
			(thermal_gap 0.0508)
		)
		(pad "A6" thru_hole circle
			(at 10.999978 0.199898 180)
			(size 0.906272 0.906272)
			(drill 0.499872)
			(layers "*.Cu" "*.Mask")
			(remove_unused_layers no)
			(net "GND")
			(clearance 0.0508)
			(thermal_gap 0.0508)
		)
		(pad "A7" thru_hole circle
			(at 13.199872 0 180)
			(size 0.71628 0.71628)
			(drill 0.30988)
			(layers "*.Cu" "*.Mask")
			(remove_unused_layers no)
			(net "PRSNT_GPU_A1_R_N")
			(clearance 0.0508)
			(thermal_gap 0.0508)
		)
		(pad "A8" thru_hole circle
			(at 15.40002 0.199898 180)
			(size 0.906272 0.906272)
			(drill 0.499872)
			(layers "*.Cu" "*.Mask")
			(remove_unused_layers no)
			(net "GND")
			(clearance 0.0508)
			(thermal_gap 0.0508)
		)
		(pad "A9" thru_hole circle
			(at 17.599914 0 180)
			(size 0.71628 0.71628)
			(drill 0.30988)
			(layers "*.Cu" "*.Mask")
			(remove_unused_layers no)
			(net "MB_3V3IO_RSVD1")
			(clearance 0.0508)
			(thermal_gap 0.0508)
		)
		(pad "A10" thru_hole circle
			(at 19.800062 0.199898 180)
			(size 0.906272 0.906272)
			(drill 0.499872)
			(layers "*.Cu" "*.Mask")
			(remove_unused_layers no)
			(net "GND")
			(clearance 0.0508)
			(thermal_gap 0.0508)
		)
		(pad "B1" thru_hole circle
			(at 0 1.299972 180)
			(size 0.906272 0.906272)
			(drill 0.499872)
			(layers "*.Cu" "*.Mask")
			(remove_unused_layers no)
			(net "GND")
			(clearance 0.0508)
			(thermal_gap 0.0508)
		)
		(pad "B3" thru_hole circle
			(at 4.400042 1.299972 180)
			(size 0.906272 0.906272)
			(drill 0.499872)
			(layers "*.Cu" "*.Mask")
			(remove_unused_layers no)
			(net "GND")
			(clearance 0.0508)
			(thermal_gap 0.0508)
		)
		(pad "B5" thru_hole circle
			(at 8.800084 1.299972 180)
			(size 0.906272 0.906272)
			(drill 0.499872)
			(layers "*.Cu" "*.Mask")
			(remove_unused_layers no)
			(net "GND")
			(clearance 0.0508)
			(thermal_gap 0.0508)
		)
		(pad "B7" thru_hole circle
			(at 13.199872 1.299972 180)
			(size 0.906272 0.906272)
			(drill 0.499872)
			(layers "*.Cu" "*.Mask")
			(remove_unused_layers no)
			(net "GND")
			(clearance 0.0508)
			(thermal_gap 0.0508)
		)
		(pad "B9" thru_hole circle
			(at 17.599914 1.299972 180)
			(size 0.906272 0.906272)
			(drill 0.499872)
			(layers "*.Cu" "*.Mask")
			(remove_unused_layers no)
			(net "GND")
			(clearance 0.0508)
			(thermal_gap 0.0508)
		)
		(pad "B10" thru_hole circle
			(at 19.800062 1.500124 180)
			(size 0.71628 0.71628)
			(drill 0.30988)
			(layers "*.Cu" "*.Mask")
			(remove_unused_layers no)
			(net "Net_8871")
			(clearance 0.0508)
			(thermal_gap 0.0508)
		)
		(pad "C9" thru_hole circle
			(at 17.599914 2.599944 180)
			(size 0.71628 0.71628)
			(drill 0.30988)
			(layers "*.Cu" "*.Mask")
			(remove_unused_layers no)
			(net "UART_MB_BIC_TX_BUF_R")
			(clearance 0.0508)
			(thermal_gap 0.0508)
		)
		(pad "C10" thru_hole circle
			(at 19.800062 2.800096 180)
			(size 0.71628 0.71628)
			(drill 0.30988)
			(layers "*.Cu" "*.Mask")
			(remove_unused_layers no)
			(net "Net_8870")
			(clearance 0.0508)
			(thermal_gap 0.0508)
		)
		(pad "D2" thru_hole circle
			(at 2.199894 4.100068 180)
			(size 0.906272 0.906272)
			(drill 0.499872)
			(layers "*.Cu" "*.Mask")
			(remove_unused_layers no)
			(net "GND")
			(clearance 0.0508)
			(thermal_gap 0.0508)
		)
		(pad "D4" thru_hole circle
			(at 6.599936 4.100068 180)
			(size 0.906272 0.906272)
			(drill 0.499872)
			(layers "*.Cu" "*.Mask")
			(remove_unused_layers no)
			(net "GND")
			(clearance 0.0508)
			(thermal_gap 0.0508)
		)
		(pad "D6" thru_hole circle
			(at 10.999978 4.100068 180)
			(size 0.906272 0.906272)
			(drill 0.499872)
			(layers "*.Cu" "*.Mask")
			(remove_unused_layers no)
			(net "GND")
			(clearance 0.0508)
			(thermal_gap 0.0508)
		)
		(pad "D8" thru_hole circle
			(at 15.40002 4.100068 180)
			(size 0.906272 0.906272)
			(drill 0.499872)
			(layers "*.Cu" "*.Mask")
			(remove_unused_layers no)
			(net "GND")
			(clearance 0.0508)
			(thermal_gap 0.0508)
		)
		(pad "D9" thru_hole circle
			(at 17.599914 3.899916 180)
			(size 0.71628 0.71628)
			(drill 0.30988)
			(layers "*.Cu" "*.Mask")
			(remove_unused_layers no)
			(net "MB_3V3IO_RSVD3")
			(clearance 0.0508)
			(thermal_gap 0.0508)
		)
		(pad "D10" thru_hole circle
			(at 19.800062 4.100068 180)
			(size 0.906272 0.906272)
			(drill 0.499872)
			(layers "*.Cu" "*.Mask")
			(remove_unused_layers no)
			(net "GND")
			(clearance 0.0508)
			(thermal_gap 0.0508)
		)
		(pad "E1" thru_hole circle
			(at 0 5.199888 180)
			(size 0.906272 0.906272)
			(drill 0.499872)
			(layers "*.Cu" "*.Mask")
			(remove_unused_layers no)
			(net "GND")
			(clearance 0.0508)
			(thermal_gap 0.0508)
		)
		(pad "E3" thru_hole circle
			(at 4.400042 5.199888 180)
			(size 0.906272 0.906272)
			(drill 0.499872)
			(layers "*.Cu" "*.Mask")
			(remove_unused_layers no)
			(net "GND")
			(clearance 0.0508)
			(thermal_gap 0.0508)
		)
		(pad "E5" thru_hole circle
			(at 8.800084 5.199888 180)
			(size 0.906272 0.906272)
			(drill 0.499872)
			(layers "*.Cu" "*.Mask")
			(remove_unused_layers no)
			(net "GND")
			(clearance 0.0508)
			(thermal_gap 0.0508)
		)
		(pad "E7" thru_hole circle
			(at 13.199872 5.199888 180)
			(size 0.906272 0.906272)
			(drill 0.499872)
			(layers "*.Cu" "*.Mask")
			(remove_unused_layers no)
			(net "GND")
			(clearance 0.0508)
			(thermal_gap 0.0508)
		)
		(pad "E9" thru_hole circle
			(at 17.599914 5.199888 180)
			(size 0.906272 0.906272)
			(drill 0.499872)
			(layers "*.Cu" "*.Mask")
			(remove_unused_layers no)
			(net "GND")
			(clearance 0.0508)
			(thermal_gap 0.0508)
		)
		(pad "E10" thru_hole circle
			(at 19.800062 5.40004 180)
			(size 0.71628 0.71628)
			(drill 0.30988)
			(layers "*.Cu" "*.Mask")
			(remove_unused_layers no)
			(net "Net_8869")
			(clearance 0.0508)
			(thermal_gap 0.0508)
		)
		(pad "F9" thru_hole circle
			(at 17.599914 6.500114 180)
			(size 0.71628 0.71628)
			(drill 0.30988)
			(layers "*.Cu" "*.Mask")
			(remove_unused_layers no)
			(net "I3C_MB_BMC_SCL")
			(clearance 0.0508)
			(thermal_gap 0.0508)
		)
		(pad "F10" thru_hole circle
			(at 19.800062 6.700012 180)
			(size 0.71628 0.71628)
			(drill 0.30988)
			(layers "*.Cu" "*.Mask")
			(remove_unused_layers no)
			(net "Net_8868")
			(clearance 0.0508)
			(thermal_gap 0.0508)
		)
		(pad "G2" thru_hole circle
			(at 2.199894 7.999984 180)
			(size 0.906272 0.906272)
			(drill 0.499872)
			(layers "*.Cu" "*.Mask")
			(remove_unused_layers no)
			(net "GND")
			(clearance 0.0508)
			(thermal_gap 0.0508)
		)
		(pad "G4" thru_hole circle
			(at 6.599936 7.999984 180)
			(size 0.906272 0.906272)
			(drill 0.499872)
			(layers "*.Cu" "*.Mask")
			(remove_unused_layers no)
			(net "GND")
			(clearance 0.0508)
			(thermal_gap 0.0508)
		)
		(pad "G6" thru_hole circle
			(at 10.999978 7.999984 180)
			(size 0.906272 0.906272)
			(drill 0.499872)
			(layers "*.Cu" "*.Mask")
			(remove_unused_layers no)
			(net "GND")
			(clearance 0.0508)
			(thermal_gap 0.0508)
		)
		(pad "G8" thru_hole circle
			(at 15.40002 7.999984 180)
			(size 0.906272 0.906272)
			(drill 0.499872)
			(layers "*.Cu" "*.Mask")
			(remove_unused_layers no)
			(net "GND")
			(clearance 0.0508)
			(thermal_gap 0.0508)
		)
		(pad "G9" thru_hole circle
			(at 17.599914 7.800086 180)
			(size 0.71628 0.71628)
			(drill 0.30988)
			(layers "*.Cu" "*.Mask")
			(remove_unused_layers no)
			(net "GPU_WP_HW_CTRL_N")
			(clearance 0.0508)
			(thermal_gap 0.0508)
		)
		(pad "G10" thru_hole circle
			(at 19.800062 7.999984 180)
			(size 0.906272 0.906272)
			(drill 0.499872)
			(layers "*.Cu" "*.Mask")
			(remove_unused_layers no)
			(net "GND")
			(clearance 0.0508)
			(thermal_gap 0.0508)
		)
		(pad "H1" thru_hole circle
			(at 0 9.100058 180)
			(size 0.906272 0.906272)
			(drill 0.499872)
			(layers "*.Cu" "*.Mask")
			(remove_unused_layers no)
			(net "GND")
			(clearance 0.0508)
			(thermal_gap 0.0508)
		)
		(pad "H3" thru_hole circle
			(at 4.400042 9.100058 180)
			(size 0.906272 0.906272)
			(drill 0.499872)
			(layers "*.Cu" "*.Mask")
			(remove_unused_layers no)
			(net "GND")
			(clearance 0.0508)
			(thermal_gap 0.0508)
		)
		(pad "H5" thru_hole circle
			(at 8.800084 9.100058 180)
			(size 0.906272 0.906272)
			(drill 0.499872)
			(layers "*.Cu" "*.Mask")
			(remove_unused_layers no)
			(net "GND")
			(clearance 0.0508)
			(thermal_gap 0.0508)
		)
		(pad "H7" thru_hole circle
			(at 13.199872 9.100058 180)
			(size 0.906272 0.906272)
			(drill 0.499872)
			(layers "*.Cu" "*.Mask")
			(remove_unused_layers no)
			(net "GND")
			(clearance 0.0508)
			(thermal_gap 0.0508)
		)
		(pad "H9" thru_hole circle
			(at 17.599914 9.100058 180)
			(size 0.906272 0.906272)
			(drill 0.499872)
			(layers "*.Cu" "*.Mask")
			(remove_unused_layers no)
			(net "GND")
			(clearance 0.0508)
			(thermal_gap 0.0508)
		)
		(pad "H10" thru_hole circle
			(at 19.800062 9.299956 180)
			(size 0.71628 0.71628)
			(drill 0.30988)
			(layers "*.Cu" "*.Mask")
			(remove_unused_layers no)
			(net "I3C_MB_BMC_SDA")
			(clearance 0.0508)
			(thermal_gap 0.0508)
		)
		(pad "I9" thru_hole circle
			(at 17.599914 10.40003 180)
			(size 0.71628 0.71628)
			(drill 0.30988)
			(layers "*.Cu" "*.Mask")
			(remove_unused_layers no)
			(net "Net_8867")
			(clearance 0.0508)
			(thermal_gap 0.0508)
		)
		(pad "I10" thru_hole circle
			(at 19.800062 10.599928 180)
			(size 0.71628 0.71628)
			(drill 0.30988)
			(layers "*.Cu" "*.Mask")
			(remove_unused_layers no)
			(net "MB_3V3IO_RSVD4")
			(clearance 0.0508)
			(thermal_gap 0.0508)
		)
		(pad "J2" thru_hole circle
			(at 2.199894 11.8999 180)
			(size 0.906272 0.906272)
			(drill 0.499872)
			(layers "*.Cu" "*.Mask")
			(remove_unused_layers no)
			(net "GND")
			(clearance 0.0508)
			(thermal_gap 0.0508)
		)
		(pad "J4" thru_hole circle
			(at 6.599936 11.8999 180)
			(size 0.906272 0.906272)
			(drill 0.499872)
			(layers "*.Cu" "*.Mask")
			(remove_unused_layers no)
			(net "GND")
			(clearance 0.0508)
			(thermal_gap 0.0508)
		)
		(pad "J6" thru_hole circle
			(at 10.999978 11.8999 180)
			(size 0.906272 0.906272)
			(drill 0.499872)
			(layers "*.Cu" "*.Mask")
			(remove_unused_layers no)
			(net "GND")
			(clearance 0.0508)
			(thermal_gap 0.0508)
		)
		(pad "J8" thru_hole circle
			(at 15.40002 11.8999 180)
			(size 0.906272 0.906272)
			(drill 0.499872)
			(layers "*.Cu" "*.Mask")
			(remove_unused_layers no)
			(net "GND")
			(clearance 0.0508)
			(thermal_gap 0.0508)
		)
		(pad "J9" thru_hole circle
			(at 17.599914 11.700002 180)
			(size 0.71628 0.71628)
			(drill 0.30988)
			(layers "*.Cu" "*.Mask")
			(remove_unused_layers no)
			(net "Net_8866")
			(clearance 0.0508)
			(thermal_gap 0.0508)
		)
		(pad "J10" thru_hole circle
			(at 19.800062 11.8999 180)
			(size 0.906272 0.906272)
			(drill 0.499872)
			(layers "*.Cu" "*.Mask")
			(remove_unused_layers no)
			(net "GND")
			(clearance 0.0508)
			(thermal_gap 0.0508)
		)
		(pad "K1" thru_hole circle
			(at 0 12.999974 180)
			(size 0.906272 0.906272)
			(drill 0.499872)
			(layers "*.Cu" "*.Mask")
			(remove_unused_layers no)
			(net "GND")
			(clearance 0.0508)
			(thermal_gap 0.0508)
		)
		(pad "K3" thru_hole circle
			(at 4.400042 12.999974 180)
			(size 0.906272 0.906272)
			(drill 0.499872)
			(layers "*.Cu" "*.Mask")
			(remove_unused_layers no)
			(net "GND")
			(clearance 0.0508)
			(thermal_gap 0.0508)
		)
		(pad "K5" thru_hole circle
			(at 8.800084 12.999974 180)
			(size 0.906272 0.906272)
			(drill 0.499872)
			(layers "*.Cu" "*.Mask")
			(remove_unused_layers no)
			(net "GND")
			(clearance 0.0508)
			(thermal_gap 0.0508)
		)
		(pad "K7" thru_hole circle
			(at 13.199872 12.999974 180)
			(size 0.906272 0.906272)
			(drill 0.499872)
			(layers "*.Cu" "*.Mask")
			(remove_unused_layers no)
			(net "GND")
			(clearance 0.0508)
			(thermal_gap 0.0508)
		)
		(pad "K9" thru_hole circle
			(at 17.599914 12.999974 180)
			(size 0.906272 0.906272)
			(drill 0.499872)
			(layers "*.Cu" "*.Mask")
			(remove_unused_layers no)
			(net "GND")
			(clearance 0.0508)
			(thermal_gap 0.0508)
		)
		(pad "K10" thru_hole circle
			(at 19.800062 13.199872 180)
			(size 0.71628 0.71628)
			(drill 0.30988)
			(layers "*.Cu" "*.Mask")
			(remove_unused_layers no)
			(net "Net_8865")
			(clearance 0.0508)
			(thermal_gap 0.0508)
		)
		(pad "L9" thru_hole circle
			(at 17.599914 14.299946 180)
			(size 0.71628 0.71628)
			(drill 0.30988)
			(layers "*.Cu" "*.Mask")
			(remove_unused_layers no)
			(net "Net_8863")
			(clearance 0.0508)
			(thermal_gap 0.0508)
		)
		(pad "L10" thru_hole circle
			(at 19.800062 14.500098 180)
			(size 0.71628 0.71628)
			(drill 0.30988)
			(layers "*.Cu" "*.Mask")
			(remove_unused_layers no)
			(net "Net_8864")
			(clearance 0.0508)
			(thermal_gap 0.0508)
		)
		(pad "M1_2" thru_hole circle
			(at 2.199894 15.80007 180)
			(size 0.906272 0.906272)
			(drill 0.499872)
			(layers "*.Cu" "*.Mask")
			(remove_unused_layers no)
			(net "GND")
			(clearance 0.0508)
			(thermal_gap 0.0508)
		)
		(pad "M1_4" thru_hole circle
			(at 6.599936 15.80007 180)
			(size 0.906272 0.906272)
			(drill 0.499872)
			(layers "*.Cu" "*.Mask")
			(remove_unused_layers no)
			(net "GND")
			(clearance 0.0508)
			(thermal_gap 0.0508)
		)
		(pad "M1_6" thru_hole circle
			(at 10.999978 15.80007 180)
			(size 0.906272 0.906272)
			(drill 0.499872)
			(layers "*.Cu" "*.Mask")
			(remove_unused_layers no)
			(net "GND")
			(clearance 0.0508)
			(thermal_gap 0.0508)
		)
		(pad "M1_8" thru_hole circle
			(at 15.40002 15.80007 180)
			(size 0.906272 0.906272)
			(drill 0.499872)
			(layers "*.Cu" "*.Mask")
			(remove_unused_layers no)
			(net "GND")
			(clearance 0.0508)
			(thermal_gap 0.0508)
		)
		(pad "M1_10" thru_hole circle
			(at 19.800062 15.80007 180)
			(size 0.906272 0.906272)
			(drill 0.499872)
			(layers "*.Cu" "*.Mask")
			(remove_unused_layers no)
			(net "GND")
			(clearance 0.0508)
			(thermal_gap 0.0508)
		)
		(pad "M2_2" thru_hole circle
			(at 2.199894 26.2001 180)
			(size 0.906272 0.906272)
			(drill 0.499872)
			(layers "*.Cu" "*.Mask")
			(remove_unused_layers no)
			(net "GND")
			(clearance 0.0508)
			(thermal_gap 0.0508)
		)
		(pad "M2_4" thru_hole circle
			(at 6.599936 26.2001 180)
			(size 0.906272 0.906272)
			(drill 0.499872)
			(layers "*.Cu" "*.Mask")
			(remove_unused_layers no)
			(net "GND")
			(clearance 0.0508)
			(thermal_gap 0.0508)
		)
		(pad "M2_6" thru_hole circle
			(at 10.999978 26.2001 180)
			(size 0.906272 0.906272)
			(drill 0.499872)
			(layers "*.Cu" "*.Mask")
			(remove_unused_layers no)
			(net "GND")
			(clearance 0.0508)
			(thermal_gap 0.0508)
		)
		(pad "M2_8" thru_hole circle
			(at 15.40002 26.2001 180)
			(size 0.906272 0.906272)
			(drill 0.499872)
			(layers "*.Cu" "*.Mask")
			(remove_unused_layers no)
			(net "GND")
			(clearance 0.0508)
			(thermal_gap 0.0508)
		)
		(pad "M2_10" thru_hole circle
			(at 19.800062 26.2001 180)
			(size 0.906272 0.906272)
			(drill 0.499872)
			(layers "*.Cu" "*.Mask")
			(remove_unused_layers no)
			(net "GND")
			(clearance 0.0508)
			(thermal_gap 0.0508)
		)
		(pad "M9" thru_hole circle
			(at 17.599914 15.599918 180)
			(size 0.71628 0.71628)
			(drill 0.30988)
			(layers "*.Cu" "*.Mask")
			(remove_unused_layers no)
			(net "Net_8862")
			(clearance 0.0508)
			(thermal_gap 0.0508)
		)
		(pad "N1_1" thru_hole circle
			(at 0 16.89989 180)
			(size 0.906272 0.906272)
			(drill 0.499872)
			(layers "*.Cu" "*.Mask")
			(remove_unused_layers no)
			(net "GND")
			(clearance 0.0508)
			(thermal_gap 0.0508)
		)
		(pad "N1_3" thru_hole circle
			(at 4.400042 16.89989 180)
			(size 0.906272 0.906272)
			(drill 0.499872)
			(layers "*.Cu" "*.Mask")
			(remove_unused_layers no)
			(net "GND")
			(clearance 0.0508)
			(thermal_gap 0.0508)
		)
		(pad "N1_5" thru_hole circle
			(at 8.800084 16.89989 180)
			(size 0.906272 0.906272)
			(drill 0.499872)
			(layers "*.Cu" "*.Mask")
			(remove_unused_layers no)
			(net "GND")
			(clearance 0.0508)
			(thermal_gap 0.0508)
		)
		(pad "N1_7" thru_hole circle
			(at 13.199872 16.89989 180)
			(size 0.906272 0.906272)
			(drill 0.499872)
			(layers "*.Cu" "*.Mask")
			(remove_unused_layers no)
			(net "GND")
			(clearance 0.0508)
			(thermal_gap 0.0508)
		)
		(pad "N1_9" thru_hole circle
			(at 17.599914 16.89989 180)
			(size 0.906272 0.906272)
			(drill 0.499872)
			(layers "*.Cu" "*.Mask")
			(remove_unused_layers no)
			(net "GND")
			(clearance 0.0508)
			(thermal_gap 0.0508)
		)
		(pad "N2_1" thru_hole circle
			(at 0 27.29992 180)
			(size 0.906272 0.906272)
			(drill 0.499872)
			(layers "*.Cu" "*.Mask")
			(remove_unused_layers no)
			(net "GND")
			(clearance 0.0508)
			(thermal_gap 0.0508)
		)
	)
)
